FILE_TYPE = CONNECTIVITY;
{Allegro Design Entry HDL 16.6-p007 (v16-6-112F) 10/10/2012}
"PAGE_NUMBER" = 66;
0"NC";
1"P3E_CPU1_PE3_MP_TXN<15:8>";
2"P3E_CPU1_PE3_MP_TXN<7:0>";
3"P3E_CPU1_PE3_MP_TXP<15:8>";
4"P3E_CPU1_PE3_MP_TXP<7:0>";
5"P3E_CPU1_PE3_MP_RXN<15:8>";
6"P3E_CPU1_PE3_MP_RXP<15:8>";
7"P3E_CPU1_PE3_MP_RXN<7:0>";
8"P3E_CPU1_PE3_MP_RXP<7:0>";
9"P3E_CPU1_PE3_MP_TXN<14>";
10"P3E_CPU1_PE3_MP_RXP<9>";
11"P3E_CPU1_PE3_MP_RXP<11>";
12"P3E_CPU1_PE3_MP_RXN<14>";
13"P3E_CPU1_PE3_MP_RXP<10>";
14"P3E_CPU1_PE3_MP_RXP<0>";
15"P3E_CPU1_PE3_MP_RXP<1>";
16"P3E_CPU1_PE3_MP_RXP<2>";
17"P3E_CPU1_PE3_MP_RXP<3>";
18"P3E_CPU1_PE3_MP_RXN<0>";
19"P3E_CPU1_PE3_MP_RXN<1>";
20"P3E_CPU1_PE3_MP_RXN<2>";
21"P3E_CPU1_PE3_MP_RXN<3>";
22"P3E_CPU1_PE3_MP_RXP<4>";
23"P3E_CPU1_PE3_MP_RXP<5>";
24"P3E_CPU1_PE3_MP_RXP<6>";
25"P3E_CPU1_PE3_MP_RXP<7>";
26"P3E_CPU1_PE3_MP_RXP<8>";
27"P3E_CPU1_PE3_MP_RXN<12>";
28"P3E_CPU1_PE3_MP_RXP<13>";
29"P3E_CPU1_PE3_MP_RXP<14>";
30"P3E_CPU1_PE3_MP_RXP<15>";
31"P3E_CPU1_PE3_MP_RXN<4>";
32"P3E_CPU1_PE3_MP_RXN<5>";
33"P3E_CPU1_PE3_MP_RXN<6>";
34"P3E_CPU1_PE3_MP_RXN<7>";
35"P3E_CPU1_PE3_MP_RXN<8>";
36"P3E_CPU1_PE3_MP_RXN<9>";
37"P3E_CPU1_PE3_MP_RXN<10>";
38"P3E_CPU1_PE3_MP_RXN<11>";
39"P3E_CPU1_PE3_MP_RXP<12>";
40"P3E_CPU1_PE3_MP_RXN<13>";
41"P3E_CPU1_PE3_MP_RXN<15>";
42"P3E_CPU1_PE3_MP_TXP<0>";
43"P3E_CPU1_PE3_MP_TXP<1>";
44"P3E_CPU1_PE3_MP_TXP<2>";
45"P3E_CPU1_PE3_MP_TXP<3>";
46"P3E_CPU1_PE3_MP_TXN<0>";
47"P3E_CPU1_PE3_MP_TXN<1>";
48"P3E_CPU1_PE3_MP_TXN<2>";
49"P3E_CPU1_PE3_MP_TXN<3>";
50"P3E_CPU1_PE3_MP_TXP<4>";
51"P3E_CPU1_PE3_MP_TXP<5>";
52"P3E_CPU1_PE3_MP_TXP<6>";
53"P3E_CPU1_PE3_MP_TXP<7>";
54"P3E_CPU1_PE3_MP_TXP<8>";
55"P3E_CPU1_PE3_MP_TXP<9>";
56"P3E_CPU1_PE3_MP_TXP<10>";
57"P3E_CPU1_PE3_MP_TXP<11>";
58"P3E_CPU1_PE3_MP_TXP<12>";
59"P3E_CPU1_PE3_MP_TXP<13>";
60"P3E_CPU1_PE3_MP_TXP<14>";
61"P3E_CPU1_PE3_MP_TXP<15>";
62"P3E_CPU1_PE3_MP_TXN<4>";
63"P3E_CPU1_PE3_MP_TXN<5>";
64"P3E_CPU1_PE3_MP_TXN<6>";
65"P3E_CPU1_PE3_MP_TXN<7>";
66"P3E_CPU1_PE3_MP_TXN<8>";
67"P3E_CPU1_PE3_MP_TXN<9>";
68"P3E_CPU1_PE3_MP_TXN<10>";
69"P3E_CPU1_PE3_MP_TXN<11>";
70"P3E_CPU1_PE3_MP_TXN<12>";
71"P3E_CPU1_PE3_MP_TXN<13>";
72"P3E_CPU1_PE3_MP_TXN<15>";
%"TAP"
"1","(-5550,1625)","2","mstr_standard","I10";
;
CDS_LIB"mstr_standard"
BODY_TYPE"PLUMBING"
HDL_TAP"TRUE";
"B \NAC \NWC"7;
"S \NAC"
BN"0"18;
%"TAP"
"1","(-5550,1675)","2","mstr_standard","I11";
;
CDS_LIB"mstr_standard"
BODY_TYPE"PLUMBING"
HDL_TAP"TRUE";
"B \NAC \NWC"7;
"S \NAC"
BN"1"19;
%"TAP"
"1","(-5550,1725)","2","mstr_standard","I12";
;
CDS_LIB"mstr_standard"
BODY_TYPE"PLUMBING"
HDL_TAP"TRUE";
"B \NAC \NWC"7;
"S \NAC"
BN"2"20;
%"TAP"
"1","(-5550,1775)","2","mstr_standard","I13";
;
CDS_LIB"mstr_standard"
BODY_TYPE"PLUMBING"
HDL_TAP"TRUE";
"B \NAC \NWC"7;
"S \NAC"
BN"3"21;
%"TAP"
"1","(-5400,1875)","2","mstr_standard","I14";
;
CDS_LIB"mstr_standard"
BODY_TYPE"PLUMBING"
HDL_TAP"TRUE";
"B \NAC \NWC"8;
"S \NAC"
BN"0"14;
%"TAP"
"1","(-5400,1925)","2","mstr_standard","I15";
;
CDS_LIB"mstr_standard"
BODY_TYPE"PLUMBING"
HDL_TAP"TRUE";
"B \NAC \NWC"8;
"S \NAC"
BN"1"15;
%"TAP"
"1","(-5400,1975)","2","mstr_standard","I16";
;
CDS_LIB"mstr_standard"
BODY_TYPE"PLUMBING"
HDL_TAP"TRUE";
"B \NAC \NWC"8;
"S \NAC"
BN"2"16;
%"TAP"
"1","(-5400,2025)","2","mstr_standard","I17";
;
CDS_LIB"mstr_standard"
BODY_TYPE"PLUMBING"
HDL_TAP"TRUE";
"B \NAC \NWC"8;
"S \NAC"
BN"3"17;
%"TAP"
"1","(-5550,2175)","2","mstr_standard","I18";
;
CDS_LIB"mstr_standard"
BODY_TYPE"PLUMBING"
HDL_TAP"TRUE";
"B \NAC \NWC"7;
"S \NAC"
BN"5"32;
%"TAP"
"1","(-5550,2125)","2","mstr_standard","I19";
;
CDS_LIB"mstr_standard"
BODY_TYPE"PLUMBING"
HDL_TAP"TRUE";
"B \NAC \NWC"7;
"S \NAC"
BN"4"31;
%"TAP"
"1","(-5550,2225)","2","mstr_standard","I20";
;
CDS_LIB"mstr_standard"
BODY_TYPE"PLUMBING"
HDL_TAP"TRUE";
"B \NAC \NWC"7;
"S \NAC"
BN"6"33;
%"TAP"
"1","(-5550,2275)","2","mstr_standard","I21";
;
CDS_LIB"mstr_standard"
BODY_TYPE"PLUMBING"
HDL_TAP"TRUE";
"B \NAC \NWC"7;
"S \NAC"
BN"7"34;
%"TAP"
"1","(-5400,2375)","2","mstr_standard","I22";
;
CDS_LIB"mstr_standard"
BODY_TYPE"PLUMBING"
HDL_TAP"TRUE";
"B \NAC \NWC"8;
"S \NAC"
BN"4"22;
%"TAP"
"1","(-5400,2425)","2","mstr_standard","I23";
;
CDS_LIB"mstr_standard"
BODY_TYPE"PLUMBING"
HDL_TAP"TRUE";
"B \NAC \NWC"8;
"S \NAC"
BN"5"23;
%"TAP"
"1","(-5400,2475)","2","mstr_standard","I24";
;
CDS_LIB"mstr_standard"
BODY_TYPE"PLUMBING"
HDL_TAP"TRUE";
"B \NAC \NWC"8;
"S \NAC"
BN"6"24;
%"TAP"
"1","(-5400,2525)","2","mstr_standard","I25";
;
CDS_LIB"mstr_standard"
BODY_TYPE"PLUMBING"
HDL_TAP"TRUE";
"B \NAC \NWC"8;
"S \NAC"
BN"7"25;
%"TAP"
"1","(-5550,2675)","2","mstr_standard","I26";
;
CDS_LIB"mstr_standard"
BODY_TYPE"PLUMBING"
HDL_TAP"TRUE";
"B \NAC \NWC"5;
"S \NAC"
BN"9"36;
%"TAP"
"1","(-5550,2625)","2","mstr_standard","I27";
;
CDS_LIB"mstr_standard"
BODY_TYPE"PLUMBING"
HDL_TAP"TRUE";
"B \NAC \NWC"5;
"S \NAC"
BN"8"35;
%"TAP"
"1","(-5550,2725)","2","mstr_standard","I28";
;
CDS_LIB"mstr_standard"
BODY_TYPE"PLUMBING"
HDL_TAP"TRUE";
"B \NAC \NWC"5;
"S \NAC"
BN"10"37;
%"TAP"
"1","(-5550,2775)","2","mstr_standard","I29";
;
CDS_LIB"mstr_standard"
BODY_TYPE"PLUMBING"
HDL_TAP"TRUE";
"B \NAC \NWC"5;
"S \NAC"
BN"11"38;
%"TAP"
"1","(-5400,2875)","2","mstr_standard","I30";
;
CDS_LIB"mstr_standard"
BODY_TYPE"PLUMBING"
HDL_TAP"TRUE";
"B \NAC \NWC"6;
"S \NAC"
BN"8"26;
%"TAP"
"1","(-5400,2925)","2","mstr_standard","I31";
;
CDS_LIB"mstr_standard"
BODY_TYPE"PLUMBING"
HDL_TAP"TRUE";
"B \NAC \NWC"6;
"S \NAC"
BN"9"10;
%"TAP"
"1","(-5400,2975)","2","mstr_standard","I32";
;
CDS_LIB"mstr_standard"
BODY_TYPE"PLUMBING"
HDL_TAP"TRUE";
"B \NAC \NWC"6;
"S \NAC"
BN"10"13;
%"TAP"
"1","(-5400,3025)","2","mstr_standard","I33";
;
CDS_LIB"mstr_standard"
BODY_TYPE"PLUMBING"
HDL_TAP"TRUE";
"B \NAC \NWC"6;
"S \NAC"
BN"11"11;
%"TAP"
"1","(-5550,3175)","2","mstr_standard","I34";
;
CDS_LIB"mstr_standard"
BODY_TYPE"PLUMBING"
HDL_TAP"TRUE";
"B \NAC \NWC"5;
"S \NAC"
BN"13"40;
%"TAP"
"1","(-5550,3375)","2","mstr_standard","I35";
;
CDS_LIB"mstr_standard"
BODY_TYPE"PLUMBING"
HDL_TAP"TRUE";
"B \NAC \NWC"5;
"S \NAC"
BN"12"27;
%"TAP"
"1","(-5550,3225)","2","mstr_standard","I36";
;
CDS_LIB"mstr_standard"
BODY_TYPE"PLUMBING"
HDL_TAP"TRUE";
"B \NAC \NWC"5;
"S \NAC"
BN"14"12;
%"TAP"
"1","(-5550,3275)","2","mstr_standard","I37";
;
CDS_LIB"mstr_standard"
BODY_TYPE"PLUMBING"
HDL_TAP"TRUE";
"B \NAC \NWC"5;
"S \NAC"
BN"15"41;
%"TAP"
"1","(-5400,3125)","2","mstr_standard","I38";
;
CDS_LIB"mstr_standard"
BODY_TYPE"PLUMBING"
HDL_TAP"TRUE";
"B \NAC \NWC"6;
"S \NAC"
BN"12"39;
%"TAP"
"1","(-5400,3425)","2","mstr_standard","I39";
;
CDS_LIB"mstr_standard"
BODY_TYPE"PLUMBING"
HDL_TAP"TRUE";
"B \NAC \NWC"6;
"S \NAC"
BN"13"28;
%"TAP"
"1","(-5400,3525)","2","mstr_standard","I40";
;
CDS_LIB"mstr_standard"
BODY_TYPE"PLUMBING"
HDL_TAP"TRUE";
"B \NAC \NWC"6;
"S \NAC"
BN"15"30;
%"TAP"
"1","(-5400,3475)","2","mstr_standard","I41";
;
CDS_LIB"mstr_standard"
BODY_TYPE"PLUMBING"
HDL_TAP"TRUE";
"B \NAC \NWC"6;
"S \NAC"
BN"14"29;
%"TAP"
"1","(-2775,1675)","0","mstr_standard","I42";
;
CDS_LIB"mstr_standard"
BODY_TYPE"PLUMBING"
HDL_TAP"TRUE";
"B \NAC \NWC"2;
"S \NAC"
BN"1"47;
%"TAP"
"1","(-2775,1625)","0","mstr_standard","I43";
;
CDS_LIB"mstr_standard"
BODY_TYPE"PLUMBING"
HDL_TAP"TRUE";
"B \NAC \NWC"2;
"S \NAC"
BN"0"46;
%"TAP"
"1","(-2775,1725)","0","mstr_standard","I44";
;
CDS_LIB"mstr_standard"
BODY_TYPE"PLUMBING"
HDL_TAP"TRUE";
"B \NAC \NWC"2;
"S \NAC"
BN"2"48;
%"TAP"
"1","(-2775,1775)","0","mstr_standard","I45";
;
CDS_LIB"mstr_standard"
BODY_TYPE"PLUMBING"
HDL_TAP"TRUE";
"B \NAC \NWC"2;
"S \NAC"
BN"3"49;
%"TAP"
"1","(-2925,1875)","0","mstr_standard","I46";
;
CDS_LIB"mstr_standard"
BODY_TYPE"PLUMBING"
HDL_TAP"TRUE";
"B \NAC \NWC"4;
"S \NAC"
BN"0"42;
%"TAP"
"1","(-2925,1975)","0","mstr_standard","I47";
;
CDS_LIB"mstr_standard"
BODY_TYPE"PLUMBING"
HDL_TAP"TRUE";
"B \NAC \NWC"4;
"S \NAC"
BN"2"44;
%"TAP"
"1","(-2925,1925)","0","mstr_standard","I48";
;
CDS_LIB"mstr_standard"
BODY_TYPE"PLUMBING"
HDL_TAP"TRUE";
"B \NAC \NWC"4;
"S \NAC"
BN"1"43;
%"TAP"
"1","(-2925,2025)","0","mstr_standard","I49";
;
CDS_LIB"mstr_standard"
BODY_TYPE"PLUMBING"
HDL_TAP"TRUE";
"B \NAC \NWC"4;
"S \NAC"
BN"3"45;
%"TAP"
"1","(-2775,2125)","0","mstr_standard","I50";
;
CDS_LIB"mstr_standard"
BODY_TYPE"PLUMBING"
HDL_TAP"TRUE";
"B \NAC \NWC"2;
"S \NAC"
BN"4"62;
%"TAP"
"1","(-2775,2175)","0","mstr_standard","I51";
;
CDS_LIB"mstr_standard"
BODY_TYPE"PLUMBING"
HDL_TAP"TRUE";
"B \NAC \NWC"2;
"S \NAC"
BN"5"63;
%"TAP"
"1","(-2775,2225)","0","mstr_standard","I52";
;
CDS_LIB"mstr_standard"
BODY_TYPE"PLUMBING"
HDL_TAP"TRUE";
"B \NAC \NWC"2;
"S \NAC"
BN"6"64;
%"TAP"
"1","(-2775,2275)","0","mstr_standard","I53";
;
CDS_LIB"mstr_standard"
BODY_TYPE"PLUMBING"
HDL_TAP"TRUE";
"B \NAC \NWC"2;
"S \NAC"
BN"7"65;
%"TAP"
"1","(-2925,2425)","0","mstr_standard","I54";
;
CDS_LIB"mstr_standard"
BODY_TYPE"PLUMBING"
HDL_TAP"TRUE";
"B \NAC \NWC"4;
"S \NAC"
BN"5"51;
%"TAP"
"1","(-2925,2375)","0","mstr_standard","I55";
;
CDS_LIB"mstr_standard"
BODY_TYPE"PLUMBING"
HDL_TAP"TRUE";
"B \NAC \NWC"4;
"S \NAC"
BN"4"50;
%"TAP"
"1","(-2925,2475)","0","mstr_standard","I56";
;
CDS_LIB"mstr_standard"
BODY_TYPE"PLUMBING"
HDL_TAP"TRUE";
"B \NAC \NWC"4;
"S \NAC"
BN"6"52;
%"TAP"
"1","(-2925,2525)","0","mstr_standard","I57";
;
CDS_LIB"mstr_standard"
BODY_TYPE"PLUMBING"
HDL_TAP"TRUE";
"B \NAC \NWC"4;
"S \NAC"
BN"7"53;
%"TAP"
"1","(-2775,2625)","0","mstr_standard","I58";
;
CDS_LIB"mstr_standard"
BODY_TYPE"PLUMBING"
HDL_TAP"TRUE";
"B \NAC \NWC"1;
"S \NAC"
BN"8"66;
%"TAP"
"1","(-2775,2725)","0","mstr_standard","I59";
;
CDS_LIB"mstr_standard"
BODY_TYPE"PLUMBING"
HDL_TAP"TRUE";
"B \NAC \NWC"1;
"S \NAC"
BN"10"68;
%"TAP"
"1","(-2775,2675)","0","mstr_standard","I60";
;
CDS_LIB"mstr_standard"
BODY_TYPE"PLUMBING"
HDL_TAP"TRUE";
"B \NAC \NWC"1;
"S \NAC"
BN"9"67;
%"TAP"
"1","(-2775,2775)","0","mstr_standard","I61";
;
CDS_LIB"mstr_standard"
BODY_TYPE"PLUMBING"
HDL_TAP"TRUE";
"B \NAC \NWC"1;
"S \NAC"
BN"11"69;
%"TAP"
"1","(-2925,2925)","0","mstr_standard","I62";
;
CDS_LIB"mstr_standard"
BODY_TYPE"PLUMBING"
HDL_TAP"TRUE";
"B \NAC \NWC"3;
"S \NAC"
BN"9"55;
%"TAP"
"1","(-2925,2875)","0","mstr_standard","I63";
;
CDS_LIB"mstr_standard"
BODY_TYPE"PLUMBING"
HDL_TAP"TRUE";
"B \NAC \NWC"3;
"S \NAC"
BN"8"54;
%"TAP"
"1","(-2925,3025)","0","mstr_standard","I64";
;
CDS_LIB"mstr_standard"
BODY_TYPE"PLUMBING"
HDL_TAP"TRUE";
"B \NAC \NWC"3;
"S \NAC"
BN"11"57;
%"TAP"
"1","(-2925,2975)","0","mstr_standard","I65";
;
CDS_LIB"mstr_standard"
BODY_TYPE"PLUMBING"
HDL_TAP"TRUE";
"B \NAC \NWC"3;
"S \NAC"
BN"10"56;
%"TAP"
"1","(-2775,3125)","0","mstr_standard","I66";
;
CDS_LIB"mstr_standard"
BODY_TYPE"PLUMBING"
HDL_TAP"TRUE";
"B \NAC \NWC"1;
"S \NAC"
BN"12"70;
%"TAP"
"1","(-2775,3175)","0","mstr_standard","I67";
;
CDS_LIB"mstr_standard"
BODY_TYPE"PLUMBING"
HDL_TAP"TRUE";
"B \NAC \NWC"1;
"S \NAC"
BN"13"71;
%"TAP"
"1","(-2775,3225)","0","mstr_standard","I68";
;
CDS_LIB"mstr_standard"
BODY_TYPE"PLUMBING"
HDL_TAP"TRUE";
"B \NAC \NWC"1;
"S \NAC"
BN"14"9;
%"TAP"
"1","(-2775,3275)","0","mstr_standard","I69";
;
CDS_LIB"mstr_standard"
BODY_TYPE"PLUMBING"
HDL_TAP"TRUE";
"B \NAC \NWC"1;
"S \NAC"
BN"15"72;
%"TAP"
"1","(-2925,3425)","0","mstr_standard","I70";
;
CDS_LIB"mstr_standard"
BODY_TYPE"PLUMBING"
HDL_TAP"TRUE";
"B \NAC \NWC"3;
"S \NAC"
BN"13"59;
%"TAP"
"1","(-2925,3375)","0","mstr_standard","I71";
;
CDS_LIB"mstr_standard"
BODY_TYPE"PLUMBING"
HDL_TAP"TRUE";
"B \NAC \NWC"3;
"S \NAC"
BN"12"58;
%"TAP"
"1","(-2925,3475)","0","mstr_standard","I72";
;
CDS_LIB"mstr_standard"
BODY_TYPE"PLUMBING"
HDL_TAP"TRUE";
"B \NAC \NWC"3;
"S \NAC"
BN"14"60;
%"TAP"
"1","(-2925,3525)","0","mstr_standard","I73";
;
CDS_LIB"mstr_standard"
BODY_TYPE"PLUMBING"
HDL_TAP"TRUE";
"B \NAC \NWC"3;
"S \NAC"
BN"15"61;
%"SKX_EXT_B"
"12","(-4125,2575)","0","chpset_lib","I84";
;
CDS_SEC"12"
LOCATION"U2D1"
PART_NUMBER"TBD"
MATERIAL"IC"
PACK_TYPE"BGA1"
SEC_TYPE"BGA1"
CDS_LIB"chpset_lib"
SEC"12"
CDS_LOCATION"U2D1";
"PE3_TX_DP<0>"
$PN"EC14"42;
"PE3_TX_DP<1>"
$PN"ED13"43;
"PE3_TX_DP<2>"
$PN"EB11"44;
"PE3_TX_DP<3>"
$PN"EA10"45;
"PE3_TX_DP<4>"
$PN"DY9"50;
"PE3_TX_DP<5>"
$PN"DV9"51;
"PE3_TX_DP<6>"
$PN"DT9"52;
"PE3_TX_DP<7>"
$PN"DP7"53;
"PE3_TX_DP<8>"
$PN"DN6"54;
"PE3_TX_DP<9>"
$PN"DM5"55;
"PE3_TX_DP<10>"
$PN"DK5"56;
"PE3_TX_DP<11>"
$PN"DH5"57;
"PE3_TX_DP<12>"
$PN"DG6"58;
"PE3_TX_DP<13>"
$PN"DC6"59;
"PE3_TX_DP<14>"
$PN"DA4"60;
"PE3_TX_DP<15>"
$PN"CV5"61;
"PE3_TX_DN<0>"
$PN"EE14"46;
"PE3_TX_DN<1>"
$PN"EE12"47;
"PE3_TX_DN<2>"
$PN"EC12"48;
"PE3_TX_DN<3>"
$PN"DY11"49;
"PE3_TX_DN<4>"
$PN"EB9"62;
"PE3_TX_DN<5>"
$PN"DW10"63;
"PE3_TX_DN<6>"
$PN"DU8"64;
"PE3_TX_DN<7>"
$PN"DR8"65;
"PE3_TX_DN<8>"
$PN"DM7"66;
"PE3_TX_DN<9>"
$PN"DP5"67;
"PE3_TX_DN<10>"
$PN"DL6"68;
"PE3_TX_DN<11>"
$PN"DJ4"69;
"PE3_TX_DN<12>"
$PN"DJ6"70;
"PE3_TX_DN<13>"
$PN"DD5"71;
"PE3_TX_DN<14>"
$PN"DB5"9;
"PE3_TX_DN<15>"
$PN"CY5"72;
"PE3_RX_DP<0>"
$PN"DY17"14;
"PE3_RX_DP<1>"
$PN"DU18"15;
"PE3_RX_DP<2>"
$PN"DV17"16;
"PE3_RX_DP<3>"
$PN"DR18"17;
"PE3_RX_DP<4>"
$PN"DN16"22;
"PE3_RX_DP<5>"
$PN"DP15"23;
"PE3_RX_DP<6>"
$PN"DM13"24;
"PE3_RX_DP<7>"
$PN"DJ14"25;
"PE3_RX_DP<8>"
$PN"DK13"26;
"PE3_RX_DP<9>"
$PN"DH11"10;
"PE3_RX_DP<10>"
$PN"DE12"13;
"PE3_RX_DP<11>"
$PN"DF11"11;
"PE3_RX_DP<12>"
$PN"DC12"27;
"PE3_RX_DP<13>"
$PN"DA12"28;
"PE3_RX_DP<14>"
$PN"CW10"29;
"PE3_RX_DP<15>"
$PN"CU10"30;
"PE3_RX_DN<0>"
$PN"EA18"18;
"PE3_RX_DN<1>"
$PN"DW18"19;
"PE3_RX_DN<2>"
$PN"DW16"20;
"PE3_RX_DN<3>"
$PN"DT19"21;
"PE3_RX_DN<4>"
$PN"DR16"31;
"PE3_RX_DN<5>"
$PN"DR14"32;
"PE3_RX_DN<6>"
$PN"DN14"33;
"PE3_RX_DN<7>"
$PN"DL14"34;
"PE3_RX_DN<8>"
$PN"DL12"35;
"PE3_RX_DN<9>"
$PN"DJ12"36;
"PE3_RX_DN<10>"
$PN"DG12"37;
"PE3_RX_DN<11>"
$PN"DG10"38;
"PE3_RX_DN<12>"
$PN"DD13"39;
"PE3_RX_DN<13>"
$PN"DB11"40;
"PE3_RX_DN<14>"
$PN"CY11"12;
"PE3_RX_DN<15>"
$PN"CV9"41;
END.
